(kicad_pcb
	(version 20241229)
	(generator "pcbnew")
	(generator_version "9.0")
	(general
		(thickness 1.6642)
		(legacy_teardrops no)
	)
	(paper "A3")
	(title_block
		(title "PolarFire SoM")
		(date "2025-07-22")
		(rev "1.1.4")
		(company "Antmicro Ltd")
		(comment 1 "www.antmicro.com")
		(comment 9 "footprints 388-392 of 470")
	)
	(layers
		(0 "F.Cu" mixed)
		(4 "In1.Cu" power)
		(6 "In2.Cu" signal)
		(8 "In3.Cu" power)
		(10 "In4.Cu" signal)
		(12 "In5.Cu" power)
		(14 "In6.Cu" power)
		(16 "In7.Cu" signal)
		(18 "In8.Cu" power)
		(20 "In9.Cu" signal)
		(22 "In10.Cu" power)
		(24 "In11.Cu" signal)
		(26 "In12.Cu" signal)
		(2 "B.Cu" mixed)
		(9 "F.Adhes" user "F.Adhesive")
		(11 "B.Adhes" user "B.Adhesive")
		(13 "F.Paste" user)
		(15 "B.Paste" user)
		(5 "F.SilkS" user "F.Silkscreen")
		(7 "B.SilkS" user "B.Silkscreen")
		(1 "F.Mask" user)
		(3 "B.Mask" user)
		(17 "Dwgs.User" user "User.Drawings")
		(19 "Cmts.User" user "User.Comments")
		(21 "Eco1.User" user "User.Eco1")
		(23 "Eco2.User" user "User.Eco2")
		(25 "Edge.Cuts" user)
		(27 "Margin" user)
		(31 "F.CrtYd" user "F.Courtyard")
		(29 "B.CrtYd" user "B.Courtyard")
		(35 "F.Fab" user)
		(33 "B.Fab" user)
	)
	(footprint "antmicro-footprints:C_0402_1005Metric"
		(layer "B.Cu")
		(at 208.12 142.62 180)
		(descr "Capacitor SMD 0402")
		(tags "capacitor SMD 0402")
		(property "Reference" "C197"
			(at -1.43 0.52 0)
			(layer "B.SilkS")
			(effects
				(font
					(size 0.7 0.7)
					(thickness 0.15)
				)
				(justify left bottom mirror)
			)
		)
		(property "Value" "C_1u_0402"
			(at -1.022927 -2.155213 0)
			(layer "B.Fab")
			(hide yes)
			(effects
				(font
					(size 0.7 0.7)
					(thickness 0.15)
				)
				(justify left bottom mirror)
			)
		)
		(property "Datasheet" "https://product.tdk.com/en/search/capacitor/ceramic/mlcc/info?part_no=C1005X6S1A105K050BC"
			(at 0 0 180)
			(layer "F.Fab")
			(hide yes)
			(effects
				(font
					(size 1.27 1.27)
					(thickness 0.15)
				)
			)
		)
		(property "Description" "SMD Multilayer Ceramic Capacitor, 1 µF, 10 V, 0402 [1005 Metric], ± 10%, X6S, C"
			(at 0 0 180)
			(layer "F.Fab")
			(hide yes)
			(effects
				(font
					(size 1.27 1.27)
					(thickness 0.15)
				)
			)
		)
		(property "Author" "Antmicro"
			(at 416.24 285.24 0)
			(layer "B.Fab")
			(hide yes)
			(effects
				(font
					(size 1 1)
					(thickness 0.15)
				)
				(justify mirror)
			)
		)
		(property "Dielectric" ""
			(at 416.24 285.24 0)
			(layer "B.Fab")
			(hide yes)
			(effects
				(font
					(size 1 1)
					(thickness 0.15)
				)
				(justify mirror)
			)
		)
		(property "License" "Apache-2.0"
			(at 416.24 285.24 0)
			(layer "B.Fab")
			(hide yes)
			(effects
				(font
					(size 1 1)
					(thickness 0.15)
				)
				(justify mirror)
			)
		)
		(property "MPN" "C1005X6S1A105K050BC"
			(at 416.24 285.24 0)
			(layer "B.Fab")
			(hide yes)
			(effects
				(font
					(size 1 1)
					(thickness 0.15)
				)
				(justify mirror)
			)
		)
		(property "Manufacturer" "TDK"
			(at 416.24 285.24 0)
			(layer "B.Fab")
			(hide yes)
			(effects
				(font
					(size 1 1)
					(thickness 0.15)
				)
				(justify mirror)
			)
		)
		(property "Public" ""
			(at 416.24 285.24 0)
			(layer "B.Fab")
			(hide yes)
			(effects
				(font
					(size 1 1)
					(thickness 0.15)
				)
				(justify mirror)
			)
		)
		(property "Val" "1u"
			(at 416.24 285.24 0)
			(layer "B.Fab")
			(hide yes)
			(effects
				(font
					(size 1 1)
					(thickness 0.15)
				)
				(justify mirror)
			)
		)
		(property "Voltage" ""
			(at 416.24 285.24 0)
			(layer "B.Fab")
			(hide yes)
			(effects
				(font
					(size 1 1)
					(thickness 0.15)
				)
				(justify mirror)
			)
		)
		(sheetname "/MIPI CrossLink/")
		(sheetfile "crosslink.kicad_sch")
		(attr smd)
		(fp_rect
			(start -0.925 0.47)
			(end 0.925 -0.47)
			(stroke
				(width 0.05)
				(type default)
			)
			(fill no)
			(layer "B.CrtYd")
		)
		(fp_line
			(start 0.504 0.25)
			(end 0.504 -0.248)
			(stroke
				(width 0.15)
				(type solid)
			)
			(layer "B.Fab")
		)
		(fp_line
			(start 0.504 -0.248)
			(end -0.494 -0.248)
			(stroke
				(width 0.15)
				(type solid)
			)
			(layer "B.Fab")
		)
		(fp_line
			(start -0.494 0.25)
			(end 0.504 0.25)
			(stroke
				(width 0.15)
				(type solid)
			)
			(layer "B.Fab")
		)
		(fp_line
			(start -0.494 -0.248)
			(end -0.494 0.25)
			(stroke
				(width 0.15)
				(type solid)
			)
			(layer "B.Fab")
		)
		(fp_text user "${REFERENCE}"
			(at -0.939 -4.599 0)
			(layer "B.Fab")
			(effects
				(font
					(size 0.7 0.7)
					(thickness 0.15)
				)
				(justify left bottom mirror)
			)
		)
		(fp_text user "Author: Antmicro"
			(at -0.939 -3.399 0)
			(layer "B.Fab")
			(effects
				(font
					(size 0.7 0.7)
					(thickness 0.15)
				)
				(justify left bottom mirror)
			)
		)
		(fp_text user "License: Apache-2.0"
			(at -0.939 -5.799 0)
			(layer "B.Fab")
			(effects
				(font
					(size 0.7 0.7)
					(thickness 0.15)
				)
				(justify left bottom mirror)
			)
		)
		(pad "1" smd roundrect
			(at -0.48 0 180)
			(size 0.59 0.64)
			(layers "B.Cu" "B.Mask" "B.Paste")
			(roundrect_rratio 0.25)
			(net 417 "GND")
			(pintype "passive")
		)
		(pad "2" smd roundrect
			(at 0.48 0 180)
			(size 0.59 0.64)
			(layers "B.Cu" "B.Mask" "B.Paste")
			(roundrect_rratio 0.25)
			(net 180 "/MIPI CrossLink/CL_VCCGPLL")
			(pintype "passive")
		)
	)
	(footprint "antmicro-footprints:C_0402_1005Metric"
		(layer "B.Cu")
		(at 213.861 119.754 180)
		(descr "Capacitor SMD 0402")
		(tags "capacitor SMD 0402")
		(property "Reference" "C115"
			(at -15.389 -13.346 0)
			(layer "B.SilkS")
			(effects
				(font
					(size 0.7 0.7)
					(thickness 0.15)
				)
				(justify left bottom mirror)
			)
		)
		(property "Value" "C_1u_0402"
			(at -1.022927 -2.155213 0)
			(layer "B.Fab")
			(hide yes)
			(effects
				(font
					(size 0.7 0.7)
					(thickness 0.15)
				)
				(justify left bottom mirror)
			)
		)
		(property "Datasheet" "https://product.tdk.com/en/search/capacitor/ceramic/mlcc/info?part_no=C1005X6S1A105K050BC"
			(at 0 0 180)
			(layer "F.Fab")
			(hide yes)
			(effects
				(font
					(size 1.27 1.27)
					(thickness 0.15)
				)
			)
		)
		(property "Description" "SMD Multilayer Ceramic Capacitor, 1 µF, 10 V, 0402 [1005 Metric], ± 10%, X6S, C"
			(at 0 0 180)
			(layer "F.Fab")
			(hide yes)
			(effects
				(font
					(size 1.27 1.27)
					(thickness 0.15)
				)
			)
		)
		(property "Author" "Antmicro"
			(at 427.722 239.508 0)
			(layer "B.Fab")
			(hide yes)
			(effects
				(font
					(size 1 1)
					(thickness 0.15)
				)
				(justify mirror)
			)
		)
		(property "Dielectric" ""
			(at 427.722 239.508 0)
			(layer "B.Fab")
			(hide yes)
			(effects
				(font
					(size 1 1)
					(thickness 0.15)
				)
				(justify mirror)
			)
		)
		(property "License" "Apache-2.0"
			(at 427.722 239.508 0)
			(layer "B.Fab")
			(hide yes)
			(effects
				(font
					(size 1 1)
					(thickness 0.15)
				)
				(justify mirror)
			)
		)
		(property "MPN" "C1005X6S1A105K050BC"
			(at 427.722 239.508 0)
			(layer "B.Fab")
			(hide yes)
			(effects
				(font
					(size 1 1)
					(thickness 0.15)
				)
				(justify mirror)
			)
		)
		(property "Manufacturer" "TDK"
			(at 427.722 239.508 0)
			(layer "B.Fab")
			(hide yes)
			(effects
				(font
					(size 1 1)
					(thickness 0.15)
				)
				(justify mirror)
			)
		)
		(property "Public" ""
			(at 427.722 239.508 0)
			(layer "B.Fab")
			(hide yes)
			(effects
				(font
					(size 1 1)
					(thickness 0.15)
				)
				(justify mirror)
			)
		)
		(property "Val" "1u"
			(at 427.722 239.508 0)
			(layer "B.Fab")
			(hide yes)
			(effects
				(font
					(size 1 1)
					(thickness 0.15)
				)
				(justify mirror)
			)
		)
		(property "Voltage" ""
			(at 427.722 239.508 0)
			(layer "B.Fab")
			(hide yes)
			(effects
				(font
					(size 1 1)
					(thickness 0.15)
				)
				(justify mirror)
			)
		)
		(sheetname "/Ethernet/")
		(sheetfile "ethernet.kicad_sch")
		(attr smd)
		(fp_rect
			(start -0.925 0.47)
			(end 0.925 -0.47)
			(stroke
				(width 0.05)
				(type default)
			)
			(fill no)
			(layer "B.CrtYd")
		)
		(fp_line
			(start 0.504 0.25)
			(end 0.504 -0.248)
			(stroke
				(width 0.15)
				(type solid)
			)
			(layer "B.Fab")
		)
		(fp_line
			(start 0.504 -0.248)
			(end -0.494 -0.248)
			(stroke
				(width 0.15)
				(type solid)
			)
			(layer "B.Fab")
		)
		(fp_line
			(start -0.494 0.25)
			(end 0.504 0.25)
			(stroke
				(width 0.15)
				(type solid)
			)
			(layer "B.Fab")
		)
		(fp_line
			(start -0.494 -0.248)
			(end -0.494 0.25)
			(stroke
				(width 0.15)
				(type solid)
			)
			(layer "B.Fab")
		)
		(fp_text user "License: Apache-2.0"
			(at -0.939 -5.799 0)
			(layer "B.Fab")
			(effects
				(font
					(size 0.7 0.7)
					(thickness 0.15)
				)
				(justify left bottom mirror)
			)
		)
		(fp_text user "${REFERENCE}"
			(at -0.939 -4.599 0)
			(layer "B.Fab")
			(effects
				(font
					(size 0.7 0.7)
					(thickness 0.15)
				)
				(justify left bottom mirror)
			)
		)
		(fp_text user "Author: Antmicro"
			(at -0.939 -3.399 0)
			(layer "B.Fab")
			(effects
				(font
					(size 0.7 0.7)
					(thickness 0.15)
				)
				(justify left bottom mirror)
			)
		)
		(pad "1" smd roundrect
			(at -0.48 0 180)
			(size 0.59 0.64)
			(layers "B.Cu" "B.Mask" "B.Paste")
			(roundrect_rratio 0.25)
			(net 417 "GND")
			(pintype "passive")
		)
		(pad "2" smd roundrect
			(at 0.48 0 180)
			(size 0.59 0.64)
			(layers "B.Cu" "B.Mask" "B.Paste")
			(roundrect_rratio 0.25)
			(net 50 "+3V3")
			(pintype "passive")
		)
	)
	(footprint "antmicro-footprints:C_0402_1005Metric"
		(layer "B.Cu")
		(at 196.09 134.72 90)
		(descr "Capacitor SMD 0402")
		(tags "capacitor SMD 0402")
		(property "Reference" "C42"
			(at 5.32 -9.59 90)
			(layer "B.SilkS")
			(effects
				(font
					(size 0.7 0.7)
					(thickness 0.15)
				)
				(justify right bottom mirror)
			)
		)
		(property "Value" "C_10n_0402"
			(at -1.022927 -2.155213 90)
			(layer "B.Fab")
			(hide yes)
			(effects
				(font
					(size 0.7 0.7)
					(thickness 0.15)
				)
				(justify right bottom mirror)
			)
		)
		(property "Datasheet" "https://www.murata.com/products/productdetail?partno=GRM155R71H103KA88%23"
			(at 0 0 90)
			(layer "F.Fab")
			(hide yes)
			(effects
				(font
					(size 1.27 1.27)
					(thickness 0.15)
				)
			)
		)
		(property "Description" "SMD Multilayer Ceramic Capacitor, 10000 pF, 50 V, 0402 [1005 Metric], ± 10%, X7R, GRM Series"
			(at 0 0 90)
			(layer "F.Fab")
			(hide yes)
			(effects
				(font
					(size 1.27 1.27)
					(thickness 0.15)
				)
			)
		)
		(property "Author" "Antmicro"
			(at 330.81 -61.37 0)
			(layer "B.Fab")
			(hide yes)
			(effects
				(font
					(size 1 1)
					(thickness 0.15)
				)
				(justify mirror)
			)
		)
		(property "Dielectric" "X7R"
			(at 330.81 -61.37 0)
			(layer "B.Fab")
			(hide yes)
			(effects
				(font
					(size 1 1)
					(thickness 0.15)
				)
				(justify mirror)
			)
		)
		(property "License" "Apache-2.0"
			(at 330.81 -61.37 0)
			(layer "B.Fab")
			(hide yes)
			(effects
				(font
					(size 1 1)
					(thickness 0.15)
				)
				(justify mirror)
			)
		)
		(property "MPN" "GRM155R71H103KA88D"
			(at 330.81 -61.37 0)
			(layer "B.Fab")
			(hide yes)
			(effects
				(font
					(size 1 1)
					(thickness 0.15)
				)
				(justify mirror)
			)
		)
		(property "Manufacturer" "Murata"
			(at 330.81 -61.37 0)
			(layer "B.Fab")
			(hide yes)
			(effects
				(font
					(size 1 1)
					(thickness 0.15)
				)
				(justify mirror)
			)
		)
		(property "Public" ""
			(at 330.81 -61.37 0)
			(layer "B.Fab")
			(hide yes)
			(effects
				(font
					(size 1 1)
					(thickness 0.15)
				)
				(justify mirror)
			)
		)
		(property "Val" "10n"
			(at 330.81 -61.37 0)
			(layer "B.Fab")
			(hide yes)
			(effects
				(font
					(size 1 1)
					(thickness 0.15)
				)
				(justify mirror)
			)
		)
		(property "Voltage" "50V"
			(at 330.81 -61.37 0)
			(layer "B.Fab")
			(hide yes)
			(effects
				(font
					(size 1 1)
					(thickness 0.15)
				)
				(justify mirror)
			)
		)
		(sheetname "/FPGA Supply/")
		(sheetfile "fpga-supply.kicad_sch")
		(attr smd)
		(fp_rect
			(start -0.925 0.47)
			(end 0.925 -0.47)
			(stroke
				(width 0.05)
				(type default)
			)
			(fill no)
			(layer "B.CrtYd")
		)
		(fp_line
			(start 0.504 -0.248)
			(end -0.494 -0.248)
			(stroke
				(width 0.15)
				(type solid)
			)
			(layer "B.Fab")
		)
		(fp_line
			(start -0.494 -0.248)
			(end -0.494 0.25)
			(stroke
				(width 0.15)
				(type solid)
			)
			(layer "B.Fab")
		)
		(fp_line
			(start 0.504 0.25)
			(end 0.504 -0.248)
			(stroke
				(width 0.15)
				(type solid)
			)
			(layer "B.Fab")
		)
		(fp_line
			(start -0.494 0.25)
			(end 0.504 0.25)
			(stroke
				(width 0.15)
				(type solid)
			)
			(layer "B.Fab")
		)
		(fp_text user "Author: Antmicro"
			(at -0.939 -3.399 270)
			(layer "B.Fab")
			(effects
				(font
					(size 0.7 0.7)
					(thickness 0.15)
				)
				(justify left bottom mirror)
			)
		)
		(fp_text user "License: Apache-2.0"
			(at -0.939 -5.799 270)
			(layer "B.Fab")
			(effects
				(font
					(size 0.7 0.7)
					(thickness 0.15)
				)
				(justify left bottom mirror)
			)
		)
		(fp_text user "${REFERENCE}"
			(at -0.939 -4.599 270)
			(layer "B.Fab")
			(effects
				(font
					(size 0.7 0.7)
					(thickness 0.15)
				)
				(justify left bottom mirror)
			)
		)
		(pad "1" smd roundrect
			(at -0.48 0 90)
			(size 0.59 0.64)
			(layers "B.Cu" "B.Mask" "B.Paste")
			(roundrect_rratio 0.25)
			(net 417 "GND")
			(pintype "passive")
		)
		(pad "2" smd roundrect
			(at 0.48 0 90)
			(size 0.59 0.64)
			(layers "B.Cu" "B.Mask" "B.Paste")
			(roundrect_rratio 0.25)
			(net 48 "+1V8")
			(pintype "passive")
		)
	)
	(footprint "antmicro-footprints:R_0402_1005Metric"
		(layer "B.Cu")
		(at 225.6 144.345 180)
		(descr "Resistor SMD 0402")
		(tags "resistor SMD 0402")
		(property "Reference" "R146"
			(at -3.8 -0.405 0)
			(layer "B.SilkS")
			(effects
				(font
					(size 0.7 0.7)
					(thickness 0.15)
				)
				(justify left bottom mirror)
			)
		)
		(property "Value" "R_10k_0402"
			(at -1.011843 -1.772047 0)
			(layer "B.Fab")
			(hide yes)
			(effects
				(font
					(size 0.7 0.7)
					(thickness 0.15)
				)
				(justify left bottom mirror)
			)
		)
		(property "Datasheet" "https://www.bourns.com/docs/product-datasheets/cr.pdf"
			(at 0 0 180)
			(layer "F.Fab")
			(hide yes)
			(effects
				(font
					(size 1.27 1.27)
					(thickness 0.15)
				)
			)
		)
		(property "Description" "SMD Chip Resistor, 10 kohm, ± 1%, 62.5 mW, 0402 [1005 Metric], Thick Film, General Purpose"
			(at 0 0 180)
			(layer "F.Fab")
			(hide yes)
			(effects
				(font
					(size 1.27 1.27)
					(thickness 0.15)
				)
			)
		)
		(property "Author" "Antmicro"
			(at 451.2 288.69 0)
			(layer "B.Fab")
			(hide yes)
			(effects
				(font
					(size 1 1)
					(thickness 0.15)
				)
				(justify mirror)
			)
		)
		(property "License" "Apache-2.0"
			(at 451.2 288.69 0)
			(layer "B.Fab")
			(hide yes)
			(effects
				(font
					(size 1 1)
					(thickness 0.15)
				)
				(justify mirror)
			)
		)
		(property "MPN" "CR0402-FX-1002GLF"
			(at 451.2 288.69 0)
			(layer "B.Fab")
			(hide yes)
			(effects
				(font
					(size 1 1)
					(thickness 0.15)
				)
				(justify mirror)
			)
		)
		(property "Manufacturer" "Bourns"
			(at 451.2 288.69 0)
			(layer "B.Fab")
			(hide yes)
			(effects
				(font
					(size 1 1)
					(thickness 0.15)
				)
				(justify mirror)
			)
		)
		(property "Public" ""
			(at 451.2 288.69 0)
			(layer "B.Fab")
			(hide yes)
			(effects
				(font
					(size 1 1)
					(thickness 0.15)
				)
				(justify mirror)
			)
		)
		(property "Tolerance" "1%"
			(at 451.2 288.69 0)
			(layer "B.Fab")
			(hide yes)
			(effects
				(font
					(size 1 1)
					(thickness 0.15)
				)
				(justify mirror)
			)
		)
		(property "Val" "10k"
			(at 451.2 288.69 0)
			(layer "B.Fab")
			(hide yes)
			(effects
				(font
					(size 1 1)
					(thickness 0.15)
				)
				(justify mirror)
			)
		)
		(sheetname "/WiFi_Bluetooth/")
		(sheetfile "wifi_bt.kicad_sch")
		(attr smd)
		(fp_rect
			(start -0.925 0.47)
			(end 0.925 -0.47)
			(stroke
				(width 0.05)
				(type default)
			)
			(fill no)
			(layer "B.CrtYd")
		)
		(fp_rect
			(start -0.5 0.25)
			(end 0.5 -0.25)
			(stroke
				(width 0.15)
				(type solid)
			)
			(fill no)
			(layer "B.Fab")
		)
		(fp_text user "License: Apache-2.0"
			(at -0.95 -5.169 0)
			(layer "B.Fab")
			(effects
				(font
					(size 0.7 0.7)
					(thickness 0.15)
				)
				(justify left bottom mirror)
			)
		)
		(fp_text user "Author: Antmicro"
			(at -0.95 -4.169 0)
			(layer "B.Fab")
			(effects
				(font
					(size 0.7 0.7)
					(thickness 0.15)
				)
				(justify left bottom mirror)
			)
		)
		(fp_text user "${REFERENCE}"
			(at -0.95 -3.168 0)
			(layer "B.Fab")
			(effects
				(font
					(size 0.7 0.7)
					(thickness 0.15)
				)
				(justify left bottom mirror)
			)
		)
		(pad "1" smd roundrect
			(at -0.48 0 180)
			(size 0.59 0.64)
			(layers "B.Cu" "B.Mask" "B.Paste")
			(roundrect_rratio 0.25)
			(net 417 "GND")
			(pintype "passive")
		)
		(pad "2" smd roundrect
			(at 0.48 0 180)
			(size 0.59 0.64)
			(layers "B.Cu" "B.Mask" "B.Paste")
			(roundrect_rratio 0.25)
			(net 422 "/WiFi_Bluetooth/STRAP_1")
			(pintype "passive")
		)
	)
	(footprint "antmicro-footprints:TP_SMD_0.75mm"
		(layer "B.Cu")
		(at 181.8 137.8 180)
		(property "Reference" "TP6"
			(at 0.325 -0.5 0)
			(layer "B.SilkS")
			(hide yes)
			(effects
				(font
					(size 0.7 0.7)
					(thickness 0.15)
				)
				(justify left bottom mirror)
			)
		)
		(property "Value" "TP_0.75mm_SMD"
			(at 0 -1.2 0)
			(layer "B.Fab")
			(hide yes)
			(effects
				(font
					(size 0.7 0.7)
					(thickness 0.15)
				)
				(justify left bottom mirror)
			)
		)
		(property "Description" "SMT test point"
			(at 0 0 0)
			(layer "B.Fab")
			(hide yes)
			(effects
				(font
					(size 1.27 1.27)
					(thickness 0.15)
				)
				(justify mirror)
			)
		)
		(property "MPN" ""
			(at 0 0 0)
			(unlocked yes)
			(layer "B.Fab")
			(hide yes)
			(effects
				(font
					(size 1 1)
					(thickness 0.15)
				)
				(justify mirror)
			)
		)
		(property "Manufacturer" ""
			(at 0 0 0)
			(unlocked yes)
			(layer "B.Fab")
			(hide yes)
			(effects
				(font
					(size 1 1)
					(thickness 0.15)
				)
				(justify mirror)
			)
		)
		(property "Author" "Antmicro"
			(at 0 0 0)
			(unlocked yes)
			(layer "B.Fab")
			(hide yes)
			(effects
				(font
					(size 1 1)
					(thickness 0.15)
				)
				(justify mirror)
			)
		)
		(property "License" "Apache-2.0"
			(at 0 0 0)
			(unlocked yes)
			(layer "B.Fab")
			(hide yes)
			(effects
				(font
					(size 1 1)
					(thickness 0.15)
				)
				(justify mirror)
			)
		)
		(property "Public" "False"
			(at 0 0 0)
			(unlocked yes)
			(layer "B.Fab")
			(hide yes)
			(effects
				(font
					(size 1 1)
					(thickness 0.15)
				)
				(justify mirror)
			)
		)
		(sheetname "/Supply/")
		(sheetfile "supply.kicad_sch")
		(attr exclude_from_pos_files exclude_from_bom)
		(fp_circle
			(center 0 0)
			(end 0.475 0)
			(stroke
				(width 0.05)
				(type default)
			)
			(fill no)
			(layer "B.CrtYd")
		)
		(fp_text user "Author: Antmicro"
			(at -0.4 -3.901 0)
			(layer "B.Fab")
			(effects
				(font
					(size 0.7 0.7)
					(thickness 0.15)
				)
				(justify left bottom mirror)
			)
		)
		(fp_text user "License: Apache-2.0"
			(at -0.4 -5.101 0)
			(layer "B.Fab")
			(effects
				(font
					(size 0.7 0.7)
					(thickness 0.15)
				)
				(justify left bottom mirror)
			)
		)
		(fp_text user "${REFERENCE}"
			(at -0.4 -2.7 0)
			(layer "B.Fab")
			(effects
				(font
					(size 0.7 0.7)
					(thickness 0.15)
				)
				(justify left bottom mirror)
			)
		)
		(pad "1" smd circle
			(at 0 0 180)
			(size 0.75 0.75)
			(layers "B.Cu" "B.Mask")
			(net 632 "Net-(U7-OUT2)")
			(pinfunction "1")
			(pintype "passive")
		)
	)
)
